(kicad_pcb
	(version 20260206)
	(generator "pcbnew")
	(generator_version "10.0")
	(general
		(thickness 1.6)
		(legacy_teardrops no)
	)
	(paper "A4")
	(title_block
		(title "Bryce Canyon_F.DPB_16315-1-OCP.brd")
		(comment 1 "Bryce Canyon / footprints 1075-1077 of 2223")
	)
	(layers
		(0 "F.Cu" signal "TOP")
		(4 "In1.Cu" signal "L2GND")
		(6 "In2.Cu" signal "L3")
		(8 "In3.Cu" signal "L4GND")
		(10 "In4.Cu" signal "L5")
		(12 "In5.Cu" signal "L6VCC")
		(14 "In6.Cu" signal "L7VCC")
		(16 "In7.Cu" signal "L8")
		(18 "In8.Cu" signal "L9GND")
		(20 "In9.Cu" signal "L10")
		(22 "In10.Cu" signal "L11GND")
		(2 "B.Cu" signal "BOTTOM")
		(9 "F.Adhes" user "F.Adhesive")
		(11 "B.Adhes" user "B.Adhesive")
		(13 "F.Paste" user "Package Geometry/Pastemask Top")
		(15 "B.Paste" user "Package Geometry/Pastemask Bottom")
		(5 "F.SilkS" user "Ref Des/Silkscreen Top")
		(7 "B.SilkS" user "Ref Des/Silkscreen Bottom")
		(1 "F.Mask" user "Board Geometry/Soldermask Top")
		(3 "B.Mask" user "Board Geometry/Soldermask Bottom")
		(17 "Dwgs.User" user "User.Drawings")
		(19 "Cmts.User" user "User.Comments")
		(21 "Eco1.User" user "User.Eco1")
		(23 "Eco2.User" user "User.Eco2")
		(25 "Edge.Cuts" user "Board Geometry/Outline")
		(27 "Margin" user)
		(31 "F.CrtYd" user "Package Geometry/Place Bound Top")
		(29 "B.CrtYd" user "Package Geometry/Place Bound Bottom")
		(35 "F.Fab" user "Ref Des/Assembly Top")
		(33 "B.Fab" user "Ref Des/Assembly Bottom")
	)
	(footprint ""
		(layer "F.Cu")
		(at 225.7044 -376.9995)
		(property "Reference" "R148"
			(at 0 0 0)
			(layer "F.SilkS")
			(hide yes)
			(effects
				(font
					(size 1.27 1.27)
				)
			)
		)
		(property "Value" "4K7R2F-GP"
			(at 0.064008 -3.993896 0)
			(unlocked yes)
			(layer "F.Fab")
			(hide yes)
			(effects
				(font
					(size 1.016 1.016)
					(thickness 0.1524)
				)
			)
		)
		(property "Device Type" "R402H16"
			(at 0.064008 -5.517896 0)
			(unlocked yes)
			(layer "F.Fab")
			(hide yes)
			(effects
				(font
					(size 1.016 1.016)
					(thickness 0.1524)
				)
			)
		)
		(duplicate_pad_numbers_are_jumpers no)
		(fp_line
			(start -0.508 -0.9398)
			(end -0.508 0.9398)
			(stroke
				(width 0.1524)
				(type default)
			)
			(layer "F.SilkS")
		)
		(fp_line
			(start 0.508 -0.9398)
			(end -0.508 -0.9398)
			(stroke
				(width 0.1524)
				(type default)
			)
			(layer "F.SilkS")
		)
		(fp_rect
			(start -0.508 0.9398)
			(end 0.508 -0.9398)
			(stroke
				(width 0)
				(type default)
			)
			(fill no)
			(layer "F.CrtYd")
		)
		(fp_rect
			(start -0.508 0.9398)
			(end 0.508 -0.9398)
			(stroke
				(width 0)
				(type default)
			)
			(fill no)
			(layer "F.Fab")
		)
		(pad "1" smd custom
			(at 0 -0.4445)
			(size 0.1397 0.1397)
			(layers "F.Cu" "F.Mask" "F.Paste")
			(net "P3V3_STBY_B")
			(options
				(clearance outline)
				(anchor circle)
			)
			(primitives
				(gr_poly
					(pts
						(arc
							(start -0.1778 -0.2794)
							(mid -0.249642 -0.249642)
							(end -0.2794 -0.1778)
						)
						(arc
							(start -0.2794 0.1778)
							(mid -0.249642 0.249642)
							(end -0.1778 0.2794)
						)
						(arc
							(start 0.1778 0.2794)
							(mid 0.249642 0.249642)
							(end 0.2794 0.1778)
						)
						(arc
							(start 0.2794 -0.1778)
							(mid 0.249642 -0.249642)
							(end 0.1778 -0.2794)
						)
					)
					(width 0)
					(fill yes)
				)
			)
		)
		(pad "2" smd custom
			(at 0 0.4445)
			(size 0.1397 0.1397)
			(layers "F.Cu" "F.Mask" "F.Paste")
			(net "IO_EXP3_HDD_FAULT_A0")
			(options
				(clearance outline)
				(anchor circle)
			)
			(primitives
				(gr_poly
					(pts
						(arc
							(start -0.1778 -0.2794)
							(mid -0.249642 -0.249642)
							(end -0.2794 -0.1778)
						)
						(arc
							(start -0.2794 0.1778)
							(mid -0.249642 0.249642)
							(end -0.1778 0.2794)
						)
						(arc
							(start 0.1778 0.2794)
							(mid 0.249642 0.249642)
							(end 0.2794 0.1778)
						)
						(arc
							(start 0.2794 -0.1778)
							(mid 0.249642 -0.249642)
							(end 0.1778 -0.2794)
						)
					)
					(width 0)
					(fill yes)
				)
			)
		)
	)
	(footprint ""
		(layer "F.Cu")
		(at 138.653266 -142.628874 -90)
		(property "Reference" "R1048"
			(at 0 0 270)
			(layer "F.SilkS")
			(hide yes)
			(effects
				(font
					(size 1.27 1.27)
				)
			)
		)
		(property "Value" "0R2J-2-GP"
			(at 0.064008 -3.993896 270)
			(unlocked yes)
			(layer "F.Fab")
			(hide yes)
			(effects
				(font
					(size 1.016 1.016)
					(thickness 0.1524)
				)
			)
		)
		(property "Device Type" "R402H16"
			(at 0.064008 -5.517896 270)
			(unlocked yes)
			(layer "F.Fab")
			(hide yes)
			(effects
				(font
					(size 1.016 1.016)
					(thickness 0.1524)
				)
			)
		)
		(duplicate_pad_numbers_are_jumpers no)
		(fp_line
			(start -0.508 -0.9398)
			(end -0.508 0.9398)
			(stroke
				(width 0.1524)
				(type default)
			)
			(layer "F.SilkS")
		)
		(fp_line
			(start 0.508 -0.9398)
			(end -0.508 -0.9398)
			(stroke
				(width 0.1524)
				(type default)
			)
			(layer "F.SilkS")
		)
		(fp_rect
			(start -0.508 0.9398)
			(end 0.508 -0.9398)
			(stroke
				(width 0)
				(type default)
			)
			(fill no)
			(layer "F.CrtYd")
		)
		(fp_rect
			(start -0.508 0.9398)
			(end 0.508 -0.9398)
			(stroke
				(width 0)
				(type default)
			)
			(fill no)
			(layer "F.Fab")
		)
		(pad "1" smd custom
			(at 0 -0.4445 270)
			(size 0.1397 0.1397)
			(layers "F.Cu" "F.Mask" "F.Paste")
			(net "MB0_SPISS_PD")
			(options
				(clearance outline)
				(anchor circle)
			)
			(primitives
				(gr_poly
					(pts
						(arc
							(start -0.1778 -0.2794)
							(mid -0.249642 -0.249642)
							(end -0.2794 -0.1778)
						)
						(arc
							(start -0.2794 0.1778)
							(mid -0.249642 0.249642)
							(end -0.1778 0.2794)
						)
						(arc
							(start 0.1778 0.2794)
							(mid 0.249642 0.249642)
							(end 0.2794 0.1778)
						)
						(arc
							(start 0.2794 -0.1778)
							(mid 0.249642 -0.249642)
							(end 0.1778 -0.2794)
						)
					)
					(width 0)
					(fill yes)
				)
			)
		)
		(pad "2" smd custom
			(at 0 0.4445 270)
			(size 0.1397 0.1397)
			(layers "F.Cu" "F.Mask" "F.Paste")
			(net "AGND_CURRENT_MONOA")
			(options
				(clearance outline)
				(anchor circle)
			)
			(primitives
				(gr_poly
					(pts
						(arc
							(start -0.1778 -0.2794)
							(mid -0.249642 -0.249642)
							(end -0.2794 -0.1778)
						)
						(arc
							(start -0.2794 0.1778)
							(mid -0.249642 0.249642)
							(end -0.1778 0.2794)
						)
						(arc
							(start 0.1778 0.2794)
							(mid 0.249642 0.249642)
							(end 0.2794 0.1778)
						)
						(arc
							(start 0.2794 -0.1778)
							(mid 0.249642 -0.249642)
							(end 0.1778 -0.2794)
						)
					)
					(width 0)
					(fill yes)
				)
			)
		)
	)
	(footprint ""
		(layer "F.Cu")
		(at 308.91607 -294.435276 180)
		(property "Reference" "R274"
			(at 0 0 180)
			(layer "F.SilkS")
			(hide yes)
			(effects
				(font
					(size 1.27 1.27)
				)
			)
		)
		(property "Value" "130R3F-GP"
			(at -0.0254 -2.5146 180)
			(unlocked yes)
			(layer "F.Fab")
			(hide yes)
			(effects
				(font
					(size 1.016 1.016)
					(thickness 0.1524)
				)
			)
		)
		(property "Device Type" "R603H22"
			(at -0.0254 -4.0386 180)
			(unlocked yes)
			(layer "F.Fab")
			(hide yes)
			(effects
				(font
					(size 1.016 1.016)
					(thickness 0.1524)
				)
			)
		)
		(duplicate_pad_numbers_are_jumpers no)
		(fp_line
			(start 0.2032 0)
			(end 0.4826 0)
			(stroke
				(width 0.2032)
				(type default)
			)
			(layer "F.SilkS")
		)
		(fp_line
			(start -0.4826 0)
			(end -0.2032 0)
			(stroke
				(width 0.2032)
				(type default)
			)
			(layer "F.SilkS")
		)
		(fp_rect
			(start -0.5842 1.3335)
			(end 0.5842 -1.3335)
			(stroke
				(width 0)
				(type default)
			)
			(fill no)
			(layer "F.CrtYd")
		)
		(fp_rect
			(start -0.5842 1.3335)
			(end 0.5842 -1.3335)
			(stroke
				(width 0)
				(type default)
			)
			(fill no)
			(layer "F.Fab")
		)
		(pad "1" smd custom
			(at 0 -0.762 180)
			(size 0.2159 0.2159)
			(layers "F.Cu" "F.Mask" "F.Paste")
			(net "P5V_B")
			(options
				(clearance outline)
				(anchor circle)
			)
			(primitives
				(gr_poly
					(pts
						(arc
							(start -0.3302 -0.4318)
							(mid -0.402042 -0.402042)
							(end -0.4318 -0.3302)
						)
						(arc
							(start -0.4318 0.3302)
							(mid -0.402042 0.402042)
							(end -0.3302 0.4318)
						)
						(arc
							(start 0.3302 0.4318)
							(mid 0.402042 0.402042)
							(end 0.4318 0.3302)
						)
						(arc
							(start 0.4318 -0.3302)
							(mid 0.402042 -0.402042)
							(end 0.3302 -0.4318)
						)
					)
					(width 0)
					(fill yes)
				)
			)
		)
		(pad "2" smd custom
			(at 0 0.762 180)
			(size 0.2159 0.2159)
			(layers "F.Cu" "F.Mask" "F.Paste")
			(net "FLT_HDD30")
			(options
				(clearance outline)
				(anchor circle)
			)
			(primitives
				(gr_poly
					(pts
						(arc
							(start -0.3302 -0.4318)
							(mid -0.402042 -0.402042)
							(end -0.4318 -0.3302)
						)
						(arc
							(start -0.4318 0.3302)
							(mid -0.402042 0.402042)
							(end -0.3302 0.4318)
						)
						(arc
							(start 0.3302 0.4318)
							(mid 0.402042 0.402042)
							(end 0.4318 0.3302)
						)
						(arc
							(start 0.4318 -0.3302)
							(mid 0.402042 -0.402042)
							(end 0.3302 -0.4318)
						)
					)
					(width 0)
					(fill yes)
				)
			)
		)
	)
)
